(kicad_pcb
	(version 20260206)
	(generator "pcbnew")
	(generator_version "10.0")
	(general
		(thickness 1.6)
		(legacy_teardrops no)
	)
	(paper "A4")
	(title_block
		(title "04192023_DAF0TMB3IC0_F0TG_MB_C_brd_V02_OCP.brd")
		(comment 1 "Grand Teton / footprints 559-567 of 8354")
	)
	(layers
		(0 "F.Cu" signal "TOP")
		(4 "In1.Cu" signal "GND")
		(6 "In2.Cu" signal "IN1")
		(8 "In3.Cu" signal "GND1")
		(10 "In4.Cu" signal "IN2")
		(12 "In5.Cu" signal "GND2")
		(14 "In6.Cu" signal "IN3")
		(16 "In7.Cu" signal "GND3")
		(18 "In8.Cu" signal "VCC")
		(20 "In9.Cu" signal "VCC1")
		(22 "In10.Cu" signal "GND4")
		(24 "In11.Cu" signal "IN4")
		(26 "In12.Cu" signal "GND5")
		(28 "In13.Cu" signal "IN5")
		(30 "In14.Cu" signal "GND6")
		(32 "In15.Cu" signal "IN6")
		(34 "In16.Cu" signal "GND7")
		(2 "B.Cu" signal "BOTTOM")
		(9 "F.Adhes" user "F.Adhesive")
		(11 "B.Adhes" user "B.Adhesive")
		(13 "F.Paste" user "Package Geometry/Pastemask Top")
		(15 "B.Paste" user "Package Geometry/Pastemask Bottom")
		(5 "F.SilkS" user "Ref Des/Silkscreen Top")
		(7 "B.SilkS" user "Ref Des/Silkscreen Bottom")
		(1 "F.Mask" user "Board Geometry/Soldermask Top")
		(3 "B.Mask" user "Board Geometry/Soldermask Bottom")
		(17 "Dwgs.User" user "User.Drawings")
		(19 "Cmts.User" user "User.Comments")
		(21 "Eco1.User" user "User.Eco1")
		(23 "Eco2.User" user "User.Eco2")
		(25 "Edge.Cuts" user "Board Geometry/Outline")
		(27 "Margin" user)
		(31 "F.CrtYd" user "Package Geometry/Place Bound Top")
		(29 "B.CrtYd" user "Package Geometry/Place Bound Bottom")
		(35 "F.Fab" user "Ref Des/Assembly Top")
		(33 "B.Fab" user "Ref Des/Assembly Bottom")
	)
	(footprint ""
		(layer "F.Cu")
		(at 153.486612 -40.04056 180)
		(property "Reference" "R3228"
			(at 0 0 180)
			(layer "F.SilkS")
			(hide yes)
			(effects
				(font
					(size 1.27 1.27)
				)
			)
		)
		(property "Value" ""
			(at 0 0 180)
			(layer "F.Fab")
			(effects
				(font
					(size 1.27 1.27)
				)
			)
		)
		(duplicate_pad_numbers_are_jumpers no)
		(fp_line
			(start 0.7874 0.4064)
			(end -0.7874 0.4064)
			(stroke
				(width 0.1524)
				(type default)
			)
			(layer "F.SilkS")
		)
		(fp_line
			(start 0.7874 -0.4064)
			(end 0.7874 0.4064)
			(stroke
				(width 0.1524)
				(type default)
			)
			(layer "F.SilkS")
		)
		(fp_line
			(start -0.7874 0.4064)
			(end -0.7874 -0.4064)
			(stroke
				(width 0.1524)
				(type default)
			)
			(layer "F.SilkS")
		)
		(fp_line
			(start -0.7874 -0.4064)
			(end 0.7874 -0.4064)
			(stroke
				(width 0.1524)
				(type default)
			)
			(layer "F.SilkS")
		)
		(fp_line
			(start 0.67945 0.3048)
			(end 0.120396 0.3048)
			(stroke
				(width 0.1)
				(type default)
			)
			(layer "F.Fab")
		)
		(fp_line
			(start 0.67945 -0.3048)
			(end 0.67945 0.3048)
			(stroke
				(width 0.1)
				(type default)
			)
			(layer "F.Fab")
		)
		(fp_line
			(start 0.12065 -0.2794)
			(end 0.12065 -0.3048)
			(stroke
				(width 0.1)
				(type default)
			)
			(layer "F.Fab")
		)
		(fp_line
			(start 0.12065 -0.3048)
			(end 0.67945 -0.3048)
			(stroke
				(width 0.1)
				(type default)
			)
			(layer "F.Fab")
		)
		(fp_line
			(start 0.120396 0.3048)
			(end 0.120396 0.2794)
			(stroke
				(width 0.1)
				(type default)
			)
			(layer "F.Fab")
		)
		(fp_line
			(start 0.120396 0.2794)
			(end -0.12065 0.2794)
			(stroke
				(width 0.1)
				(type default)
			)
			(layer "F.Fab")
		)
		(fp_line
			(start -0.12065 0.3048)
			(end -0.67945 0.3048)
			(stroke
				(width 0.1)
				(type default)
			)
			(layer "F.Fab")
		)
		(fp_line
			(start -0.12065 0.2794)
			(end -0.12065 0.3048)
			(stroke
				(width 0.1)
				(type default)
			)
			(layer "F.Fab")
		)
		(fp_line
			(start -0.12065 -0.2794)
			(end 0.12065 -0.2794)
			(stroke
				(width 0.1)
				(type default)
			)
			(layer "F.Fab")
		)
		(fp_line
			(start -0.12065 -0.305054)
			(end -0.12065 -0.2794)
			(stroke
				(width 0.1)
				(type default)
			)
			(layer "F.Fab")
		)
		(fp_line
			(start -0.67945 0.3048)
			(end -0.67945 -0.305054)
			(stroke
				(width 0.1)
				(type default)
			)
			(layer "F.Fab")
		)
		(fp_line
			(start -0.67945 -0.305054)
			(end -0.12065 -0.305054)
			(stroke
				(width 0.1)
				(type default)
			)
			(layer "F.Fab")
		)
		(pad "1" smd circle
			(at -0.40005 0 180)
			(size 0 0)
			(layers "F.Cu" "F.Mask" "F.Paste")
			(net "SMB_OCP_V3_2_3V3AUX_BUF_R_SCL")
		)
		(pad "2" smd circle
			(at 0.40005 0 180)
			(size 0 0)
			(layers "F.Cu" "F.Mask" "F.Paste")
			(net "SMB_OCP_V3_2_3V3AUX_BUF_SCL")
		)
	)
	(footprint ""
		(layer "F.Cu")
		(at 394.981938 -395.1732 90)
		(property "Reference" "R1098"
			(at 0 0 90)
			(layer "F.SilkS")
			(hide yes)
			(effects
				(font
					(size 1.27 1.27)
				)
			)
		)
		(property "Value" ""
			(at 0 0 90)
			(layer "F.Fab")
			(effects
				(font
					(size 1.27 1.27)
				)
			)
		)
		(duplicate_pad_numbers_are_jumpers no)
		(fp_line
			(start 0.32512 -0.175006)
			(end 0.32512 0.175006)
			(stroke
				(width 0.1)
				(type default)
			)
			(layer "F.Fab")
		)
		(fp_line
			(start -0.32512 -0.175006)
			(end 0.32512 -0.175006)
			(stroke
				(width 0.1)
				(type default)
			)
			(layer "F.Fab")
		)
		(fp_line
			(start 0.32512 0.175006)
			(end -0.32512 0.175006)
			(stroke
				(width 0.1)
				(type default)
			)
			(layer "F.Fab")
		)
		(fp_line
			(start -0.32512 0.175006)
			(end -0.32512 -0.175006)
			(stroke
				(width 0.1)
				(type default)
			)
			(layer "F.Fab")
		)
		(pad "1" smd rect
			(at -0.2667 0 90)
			(size 0.3048 0.381)
			(layers "F.Cu" "F.Mask" "F.Paste")
			(net "RT_CPU0_P3_ADDR3")
		)
		(pad "2" smd rect
			(at 0.2667 0 270)
			(size 0.3048 0.381)
			(layers "F.Cu" "F.Mask" "F.Paste")
			(net "GND")
		)
	)
	(footprint ""
		(layer "F.Cu")
		(at 104.741726 -397.13408 180)
		(property "Reference" "C7501"
			(at 0 0 180)
			(layer "F.SilkS")
			(hide yes)
			(effects
				(font
					(size 1.27 1.27)
				)
			)
		)
		(property "Value" ""
			(at 0 0 180)
			(layer "F.Fab")
			(effects
				(font
					(size 1.27 1.27)
				)
			)
		)
		(duplicate_pad_numbers_are_jumpers no)
		(fp_line
			(start 0.299974 0.150114)
			(end -0.299974 0.150114)
			(stroke
				(width 0.1)
				(type default)
			)
			(layer "F.Fab")
		)
		(fp_line
			(start 0.299974 -0.150114)
			(end 0.299974 0.150114)
			(stroke
				(width 0.1)
				(type default)
			)
			(layer "F.Fab")
		)
		(fp_line
			(start -0.299974 0.150114)
			(end -0.299974 -0.150114)
			(stroke
				(width 0.1)
				(type default)
			)
			(layer "F.Fab")
		)
		(fp_line
			(start -0.299974 -0.150114)
			(end 0.299974 -0.150114)
			(stroke
				(width 0.1)
				(type default)
			)
			(layer "F.Fab")
		)
		(pad "1" smd rect
			(at -0.2667 0 180)
			(size 0.3048 0.381)
			(layers "F.Cu" "F.Mask" "F.Paste")
			(net "P1V8_CPU1_RT_1D")
		)
		(pad "2" smd rect
			(at 0.2667 0 180)
			(size 0.3048 0.381)
			(layers "F.Cu" "F.Mask" "F.Paste")
			(net "GND")
		)
	)
	(footprint ""
		(layer "F.Cu")
		(at 433.1716 -17.624298 90)
		(property "Reference" "C1579"
			(at 0 0 90)
			(layer "F.SilkS")
			(hide yes)
			(effects
				(font
					(size 1.27 1.27)
				)
			)
		)
		(property "Value" ""
			(at 0 0 90)
			(layer "F.Fab")
			(effects
				(font
					(size 1.27 1.27)
				)
			)
		)
		(duplicate_pad_numbers_are_jumpers no)
		(fp_line
			(start 0.299974 -0.150114)
			(end 0.299974 0.150114)
			(stroke
				(width 0.1)
				(type default)
			)
			(layer "F.Fab")
		)
		(fp_line
			(start -0.299974 -0.150114)
			(end 0.299974 -0.150114)
			(stroke
				(width 0.1)
				(type default)
			)
			(layer "F.Fab")
		)
		(fp_line
			(start 0.299974 0.150114)
			(end -0.299974 0.150114)
			(stroke
				(width 0.1)
				(type default)
			)
			(layer "F.Fab")
		)
		(fp_line
			(start -0.299974 0.150114)
			(end -0.299974 -0.150114)
			(stroke
				(width 0.1)
				(type default)
			)
			(layer "F.Fab")
		)
		(pad "1" smd rect
			(at -0.2667 0 90)
			(size 0.3048 0.381)
			(layers "F.Cu" "F.Mask" "F.Paste")
			(net "P5E_CPU0_G3_TX_C_DP<0>")
		)
		(pad "2" smd rect
			(at 0.2667 0 90)
			(size 0.3048 0.381)
			(layers "F.Cu" "F.Mask" "F.Paste")
			(net "P5E_CPU0_G3_TX_DP<0>")
		)
	)
	(footprint ""
		(layer "F.Cu")
		(at 367.685066 -424.002962 90)
		(property "Reference" "R4207"
			(at 0 0 90)
			(layer "F.SilkS")
			(hide yes)
			(effects
				(font
					(size 1.27 1.27)
				)
			)
		)
		(property "Value" ""
			(at 0 0 90)
			(layer "F.Fab")
			(effects
				(font
					(size 1.27 1.27)
				)
			)
		)
		(duplicate_pad_numbers_are_jumpers no)
		(fp_line
			(start 0.7874 -0.4064)
			(end 0.7874 0.4064)
			(stroke
				(width 0.1524)
				(type default)
			)
			(layer "F.SilkS")
		)
		(fp_line
			(start -0.7874 -0.4064)
			(end 0.7874 -0.4064)
			(stroke
				(width 0.1524)
				(type default)
			)
			(layer "F.SilkS")
		)
		(fp_line
			(start 0.7874 0.4064)
			(end -0.7874 0.4064)
			(stroke
				(width 0.1524)
				(type default)
			)
			(layer "F.SilkS")
		)
		(fp_line
			(start -0.7874 0.4064)
			(end -0.7874 -0.4064)
			(stroke
				(width 0.1524)
				(type default)
			)
			(layer "F.SilkS")
		)
		(fp_line
			(start -0.12065 -0.305054)
			(end -0.12065 -0.2794)
			(stroke
				(width 0.1)
				(type default)
			)
			(layer "F.Fab")
		)
		(fp_line
			(start -0.67945 -0.305054)
			(end -0.12065 -0.305054)
			(stroke
				(width 0.1)
				(type default)
			)
			(layer "F.Fab")
		)
		(fp_line
			(start 0.67945 -0.3048)
			(end 0.67945 0.3048)
			(stroke
				(width 0.1)
				(type default)
			)
			(layer "F.Fab")
		)
		(fp_line
			(start 0.12065 -0.3048)
			(end 0.67945 -0.3048)
			(stroke
				(width 0.1)
				(type default)
			)
			(layer "F.Fab")
		)
		(fp_line
			(start 0.12065 -0.2794)
			(end 0.12065 -0.3048)
			(stroke
				(width 0.1)
				(type default)
			)
			(layer "F.Fab")
		)
		(fp_line
			(start -0.12065 -0.2794)
			(end 0.12065 -0.2794)
			(stroke
				(width 0.1)
				(type default)
			)
			(layer "F.Fab")
		)
		(fp_line
			(start 0.120396 0.2794)
			(end -0.12065 0.2794)
			(stroke
				(width 0.1)
				(type default)
			)
			(layer "F.Fab")
		)
		(fp_line
			(start -0.12065 0.2794)
			(end -0.12065 0.3048)
			(stroke
				(width 0.1)
				(type default)
			)
			(layer "F.Fab")
		)
		(fp_line
			(start 0.67945 0.3048)
			(end 0.120396 0.3048)
			(stroke
				(width 0.1)
				(type default)
			)
			(layer "F.Fab")
		)
		(fp_line
			(start 0.120396 0.3048)
			(end 0.120396 0.2794)
			(stroke
				(width 0.1)
				(type default)
			)
			(layer "F.Fab")
		)
		(fp_line
			(start -0.12065 0.3048)
			(end -0.67945 0.3048)
			(stroke
				(width 0.1)
				(type default)
			)
			(layer "F.Fab")
		)
		(fp_line
			(start -0.67945 0.3048)
			(end -0.67945 -0.305054)
			(stroke
				(width 0.1)
				(type default)
			)
			(layer "F.Fab")
		)
		(pad "1" smd circle
			(at -0.40005 0 90)
			(size 0 0)
			(layers "F.Cu" "F.Mask" "F.Paste")
			(net "U270_0_ADD0")
		)
		(pad "2" smd circle
			(at 0.40005 0 90)
			(size 0 0)
			(layers "F.Cu" "F.Mask" "F.Paste")
			(net "GND")
		)
	)
	(footprint ""
		(layer "F.Cu")
		(at 197.269608 -125.817376)
		(property "Reference" "R3479"
			(at 0 0 0)
			(layer "F.SilkS")
			(hide yes)
			(effects
				(font
					(size 1.27 1.27)
				)
			)
		)
		(property "Value" ""
			(at 0 0 0)
			(layer "F.Fab")
			(effects
				(font
					(size 1.27 1.27)
				)
			)
		)
		(duplicate_pad_numbers_are_jumpers no)
		(fp_line
			(start -0.7874 -0.4064)
			(end 0.7874 -0.4064)
			(stroke
				(width 0.1524)
				(type default)
			)
			(layer "F.SilkS")
		)
		(fp_line
			(start -0.7874 0.4064)
			(end -0.7874 -0.4064)
			(stroke
				(width 0.1524)
				(type default)
			)
			(layer "F.SilkS")
		)
		(fp_line
			(start 0.7874 -0.4064)
			(end 0.7874 0.4064)
			(stroke
				(width 0.1524)
				(type default)
			)
			(layer "F.SilkS")
		)
		(fp_line
			(start 0.7874 0.4064)
			(end -0.7874 0.4064)
			(stroke
				(width 0.1524)
				(type default)
			)
			(layer "F.SilkS")
		)
		(fp_line
			(start -0.67945 -0.305054)
			(end -0.12065 -0.305054)
			(stroke
				(width 0.1)
				(type default)
			)
			(layer "F.Fab")
		)
		(fp_line
			(start -0.67945 0.3048)
			(end -0.67945 -0.305054)
			(stroke
				(width 0.1)
				(type default)
			)
			(layer "F.Fab")
		)
		(fp_line
			(start -0.12065 -0.305054)
			(end -0.12065 -0.2794)
			(stroke
				(width 0.1)
				(type default)
			)
			(layer "F.Fab")
		)
		(fp_line
			(start -0.12065 -0.2794)
			(end 0.12065 -0.2794)
			(stroke
				(width 0.1)
				(type default)
			)
			(layer "F.Fab")
		)
		(fp_line
			(start -0.12065 0.2794)
			(end -0.12065 0.3048)
			(stroke
				(width 0.1)
				(type default)
			)
			(layer "F.Fab")
		)
		(fp_line
			(start -0.12065 0.3048)
			(end -0.67945 0.3048)
			(stroke
				(width 0.1)
				(type default)
			)
			(layer "F.Fab")
		)
		(fp_line
			(start 0.120396 0.2794)
			(end -0.12065 0.2794)
			(stroke
				(width 0.1)
				(type default)
			)
			(layer "F.Fab")
		)
		(fp_line
			(start 0.120396 0.3048)
			(end 0.120396 0.2794)
			(stroke
				(width 0.1)
				(type default)
			)
			(layer "F.Fab")
		)
		(fp_line
			(start 0.12065 -0.3048)
			(end 0.67945 -0.3048)
			(stroke
				(width 0.1)
				(type default)
			)
			(layer "F.Fab")
		)
		(fp_line
			(start 0.12065 -0.2794)
			(end 0.12065 -0.3048)
			(stroke
				(width 0.1)
				(type default)
			)
			(layer "F.Fab")
		)
		(fp_line
			(start 0.67945 -0.3048)
			(end 0.67945 0.3048)
			(stroke
				(width 0.1)
				(type default)
			)
			(layer "F.Fab")
		)
		(fp_line
			(start 0.67945 0.3048)
			(end 0.120396 0.3048)
			(stroke
				(width 0.1)
				(type default)
			)
			(layer "F.Fab")
		)
		(pad "1" smd circle
			(at -0.40005 0)
			(size 0 0)
			(layers "F.Cu" "F.Mask" "F.Paste")
			(net "GPU_BASE_STBY_EN_R")
		)
		(pad "2" smd circle
			(at 0.40005 0)
			(size 0 0)
			(layers "F.Cu" "F.Mask" "F.Paste")
			(net "GPU_BASE_STBY_EN")
		)
	)
	(footprint ""
		(layer "F.Cu")
		(at 146.415506 -408.517344 -90)
		(property "Reference" "C6713"
			(at 0 0 270)
			(layer "F.SilkS")
			(hide yes)
			(effects
				(font
					(size 1.27 1.27)
				)
			)
		)
		(property "Value" ""
			(at 0 0 270)
			(layer "F.Fab")
			(effects
				(font
					(size 1.27 1.27)
				)
			)
		)
		(duplicate_pad_numbers_are_jumpers no)
		(fp_line
			(start -0.299974 0.150114)
			(end -0.299974 -0.150114)
			(stroke
				(width 0.1)
				(type default)
			)
			(layer "F.Fab")
		)
		(fp_line
			(start 0.299974 0.150114)
			(end -0.299974 0.150114)
			(stroke
				(width 0.1)
				(type default)
			)
			(layer "F.Fab")
		)
		(fp_line
			(start -0.299974 -0.150114)
			(end 0.299974 -0.150114)
			(stroke
				(width 0.1)
				(type default)
			)
			(layer "F.Fab")
		)
		(fp_line
			(start 0.299974 -0.150114)
			(end 0.299974 0.150114)
			(stroke
				(width 0.1)
				(type default)
			)
			(layer "F.Fab")
		)
		(pad "1" smd rect
			(at -0.2667 0 270)
			(size 0.3048 0.381)
			(layers "F.Cu" "F.Mask" "F.Paste")
			(net "P5E_CPU1_P2_TX_BUF_C_DP<10>")
		)
		(pad "2" smd rect
			(at 0.2667 0 270)
			(size 0.3048 0.381)
			(layers "F.Cu" "F.Mask" "F.Paste")
			(net "P5E_CPU1_P2_TX_BUF_DP<10>")
		)
	)
	(footprint ""
		(layer "F.Cu")
		(at 43.265852 -385.58216)
		(property "Reference" "R707"
			(at 0 0 0)
			(layer "F.SilkS")
			(hide yes)
			(effects
				(font
					(size 1.27 1.27)
				)
			)
		)
		(property "Value" ""
			(at 0 0 0)
			(layer "F.Fab")
			(effects
				(font
					(size 1.27 1.27)
				)
			)
		)
		(duplicate_pad_numbers_are_jumpers no)
		(fp_line
			(start -0.32512 -0.175006)
			(end 0.32512 -0.175006)
			(stroke
				(width 0.1)
				(type default)
			)
			(layer "F.Fab")
		)
		(fp_line
			(start -0.32512 0.175006)
			(end -0.32512 -0.175006)
			(stroke
				(width 0.1)
				(type default)
			)
			(layer "F.Fab")
		)
		(fp_line
			(start 0.32512 -0.175006)
			(end 0.32512 0.175006)
			(stroke
				(width 0.1)
				(type default)
			)
			(layer "F.Fab")
		)
		(fp_line
			(start 0.32512 0.175006)
			(end -0.32512 0.175006)
			(stroke
				(width 0.1)
				(type default)
			)
			(layer "F.Fab")
		)
		(pad "1" smd rect
			(at -0.2667 0)
			(size 0.3048 0.381)
			(layers "F.Cu" "F.Mask" "F.Paste")
			(net "GPIO2_RT_CPU1_P0")
		)
		(pad "2" smd rect
			(at 0.2667 0 180)
			(size 0.3048 0.381)
			(layers "F.Cu" "F.Mask" "F.Paste")
			(net "GND")
		)
	)
	(footprint ""
		(layer "F.Cu")
		(at 89.922604 -178.024028 -90)
		(property "Reference" "PR190"
			(at 0 0 270)
			(layer "F.SilkS")
			(hide yes)
			(effects
				(font
					(size 1.27 1.27)
				)
			)
		)
		(property "Value" ""
			(at 0 0 270)
			(layer "F.Fab")
			(effects
				(font
					(size 1.27 1.27)
				)
			)
		)
		(duplicate_pad_numbers_are_jumpers no)
		(fp_line
			(start -0.7874 0.4064)
			(end -0.7874 -0.4064)
			(stroke
				(width 0.1524)
				(type default)
			)
			(layer "F.SilkS")
		)
		(fp_line
			(start 0.7874 0.4064)
			(end -0.7874 0.4064)
			(stroke
				(width 0.1524)
				(type default)
			)
			(layer "F.SilkS")
		)
		(fp_line
			(start -0.7874 -0.4064)
			(end 0.7874 -0.4064)
			(stroke
				(width 0.1524)
				(type default)
			)
			(layer "F.SilkS")
		)
		(fp_line
			(start 0.7874 -0.4064)
			(end 0.7874 0.4064)
			(stroke
				(width 0.1524)
				(type default)
			)
			(layer "F.SilkS")
		)
		(fp_line
			(start -0.67945 0.3048)
			(end -0.67945 -0.305054)
			(stroke
				(width 0.1)
				(type default)
			)
			(layer "F.Fab")
		)
		(fp_line
			(start -0.12065 0.3048)
			(end -0.67945 0.3048)
			(stroke
				(width 0.1)
				(type default)
			)
			(layer "F.Fab")
		)
		(fp_line
			(start 0.120396 0.3048)
			(end 0.120396 0.2794)
			(stroke
				(width 0.1)
				(type default)
			)
			(layer "F.Fab")
		)
		(fp_line
			(start 0.67945 0.3048)
			(end 0.120396 0.3048)
			(stroke
				(width 0.1)
				(type default)
			)
			(layer "F.Fab")
		)
		(fp_line
			(start -0.12065 0.2794)
			(end -0.12065 0.3048)
			(stroke
				(width 0.1)
				(type default)
			)
			(layer "F.Fab")
		)
		(fp_line
			(start 0.120396 0.2794)
			(end -0.12065 0.2794)
			(stroke
				(width 0.1)
				(type default)
			)
			(layer "F.Fab")
		)
		(fp_line
			(start -0.12065 -0.2794)
			(end 0.12065 -0.2794)
			(stroke
				(width 0.1)
				(type default)
			)
			(layer "F.Fab")
		)
		(fp_line
			(start 0.12065 -0.2794)
			(end 0.12065 -0.3048)
			(stroke
				(width 0.1)
				(type default)
			)
			(layer "F.Fab")
		)
		(fp_line
			(start 0.12065 -0.3048)
			(end 0.67945 -0.3048)
			(stroke
				(width 0.1)
				(type default)
			)
			(layer "F.Fab")
		)
		(fp_line
			(start 0.67945 -0.3048)
			(end 0.67945 0.3048)
			(stroke
				(width 0.1)
				(type default)
			)
			(layer "F.Fab")
		)
		(fp_line
			(start -0.67945 -0.305054)
			(end -0.12065 -0.305054)
			(stroke
				(width 0.1)
				(type default)
			)
			(layer "F.Fab")
		)
		(fp_line
			(start -0.12065 -0.305054)
			(end -0.12065 -0.2794)
			(stroke
				(width 0.1)
				(type default)
			)
			(layer "F.Fab")
		)
		(pad "1" smd circle
			(at -0.40005 0 270)
			(size 0 0)
			(layers "F.Cu" "F.Mask" "F.Paste")
			(net "SW_PVDDCR_CPU0_P1_BOOT2")
		)
		(pad "2" smd circle
			(at 0.40005 0 270)
			(size 0 0)
			(layers "F.Cu" "F.Mask" "F.Paste")
			(net "SW_PVDDCR_CPU0_P1_BOOT2_RC")
		)
	)
)
